#ISCELL
  pure_quanta quanta_title_block_c *
  *
#ISCELL
  logical_power universal_power *
  page178_i10
#CELL
  pure_quanta emmitsburg_rev0p9 *
  page178_i11
#ISCELL
  logical_power universal_power *
  page178_i17
#ISCELL
  logical_power universal_gnd *
  page178_i18
#ISCELL
  logical_power universal_power *
  page178_i2
#ISCELL
  logical_power universal_power *
  page178_i5
#ISCELL
  logical_power universal_power *
  page178_i6
#ISCELL
  logical_power universal_power *
  page178_i7
#ISCELL
  logical_power universal_power *
  page178_i8
#ISCELL
  logical_power universal_power *
  page178_i9
